(kicad_pcb
	(version 20260206)
	(generator "pcbnew")
	(generator_version "10.0")
	(general
		(thickness 1.6)
		(legacy_teardrops no)
	)
	(paper "A4")
	(title_block
		(title "04192023_DAF0TMB3IC0_F0TG_MB_C_brd_V02_OCP.brd")
		(comment 1 "Grand Teton / footprints 597-604 of 8354")
	)
	(layers
		(0 "F.Cu" signal "TOP")
		(4 "In1.Cu" signal "GND")
		(6 "In2.Cu" signal "IN1")
		(8 "In3.Cu" signal "GND1")
		(10 "In4.Cu" signal "IN2")
		(12 "In5.Cu" signal "GND2")
		(14 "In6.Cu" signal "IN3")
		(16 "In7.Cu" signal "GND3")
		(18 "In8.Cu" signal "VCC")
		(20 "In9.Cu" signal "VCC1")
		(22 "In10.Cu" signal "GND4")
		(24 "In11.Cu" signal "IN4")
		(26 "In12.Cu" signal "GND5")
		(28 "In13.Cu" signal "IN5")
		(30 "In14.Cu" signal "GND6")
		(32 "In15.Cu" signal "IN6")
		(34 "In16.Cu" signal "GND7")
		(2 "B.Cu" signal "BOTTOM")
		(9 "F.Adhes" user "F.Adhesive")
		(11 "B.Adhes" user "B.Adhesive")
		(13 "F.Paste" user "Package Geometry/Pastemask Top")
		(15 "B.Paste" user "Package Geometry/Pastemask Bottom")
		(5 "F.SilkS" user "Ref Des/Silkscreen Top")
		(7 "B.SilkS" user "Ref Des/Silkscreen Bottom")
		(1 "F.Mask" user "Board Geometry/Soldermask Top")
		(3 "B.Mask" user "Board Geometry/Soldermask Bottom")
		(17 "Dwgs.User" user "User.Drawings")
		(19 "Cmts.User" user "User.Comments")
		(21 "Eco1.User" user "User.Eco1")
		(23 "Eco2.User" user "User.Eco2")
		(25 "Edge.Cuts" user "Board Geometry/Outline")
		(27 "Margin" user)
		(31 "F.CrtYd" user "Package Geometry/Place Bound Top")
		(29 "B.CrtYd" user "Package Geometry/Place Bound Bottom")
		(35 "F.Fab" user "Ref Des/Assembly Top")
		(33 "B.Fab" user "Ref Des/Assembly Bottom")
	)
	(footprint ""
		(layer "F.Cu")
		(at 130.49758 -26.99258 -90)
		(property "Reference" "R6192"
			(at 0 0 270)
			(layer "F.SilkS")
			(hide yes)
			(effects
				(font
					(size 1.27 1.27)
				)
			)
		)
		(property "Value" ""
			(at 0 0 270)
			(layer "F.Fab")
			(effects
				(font
					(size 1.27 1.27)
				)
			)
		)
		(duplicate_pad_numbers_are_jumpers no)
		(fp_line
			(start -0.32512 0.175006)
			(end -0.32512 -0.175006)
			(stroke
				(width 0.1)
				(type default)
			)
			(layer "F.Fab")
		)
		(fp_line
			(start 0.32512 0.175006)
			(end -0.32512 0.175006)
			(stroke
				(width 0.1)
				(type default)
			)
			(layer "F.Fab")
		)
		(fp_line
			(start -0.32512 -0.175006)
			(end 0.32512 -0.175006)
			(stroke
				(width 0.1)
				(type default)
			)
			(layer "F.Fab")
		)
		(fp_line
			(start 0.32512 -0.175006)
			(end 0.32512 0.175006)
			(stroke
				(width 0.1)
				(type default)
			)
			(layer "F.Fab")
		)
		(pad "1" smd rect
			(at -0.2667 0 270)
			(size 0.3048 0.381)
			(layers "F.Cu" "F.Mask" "F.Paste")
			(net "USB2_CPU0_P0_DP")
		)
		(pad "2" smd rect
			(at 0.2667 0 90)
			(size 0.3048 0.381)
			(layers "F.Cu" "F.Mask" "F.Paste")
			(net "USB2_CPU0_P0_R2_DP")
		)
	)
	(footprint ""
		(layer "F.Cu")
		(at 30.392878 -17.623536 90)
		(property "Reference" "C689"
			(at 0 0 90)
			(layer "F.SilkS")
			(hide yes)
			(effects
				(font
					(size 1.27 1.27)
				)
			)
		)
		(property "Value" ""
			(at 0 0 90)
			(layer "F.Fab")
			(effects
				(font
					(size 1.27 1.27)
				)
			)
		)
		(duplicate_pad_numbers_are_jumpers no)
		(fp_line
			(start 0.299974 -0.150114)
			(end 0.299974 0.150114)
			(stroke
				(width 0.1)
				(type default)
			)
			(layer "F.Fab")
		)
		(fp_line
			(start -0.299974 -0.150114)
			(end 0.299974 -0.150114)
			(stroke
				(width 0.1)
				(type default)
			)
			(layer "F.Fab")
		)
		(fp_line
			(start 0.299974 0.150114)
			(end -0.299974 0.150114)
			(stroke
				(width 0.1)
				(type default)
			)
			(layer "F.Fab")
		)
		(fp_line
			(start -0.299974 0.150114)
			(end -0.299974 -0.150114)
			(stroke
				(width 0.1)
				(type default)
			)
			(layer "F.Fab")
		)
		(pad "1" smd rect
			(at -0.2667 0 90)
			(size 0.3048 0.381)
			(layers "F.Cu" "F.Mask" "F.Paste")
			(net "P5E_CPU1_G1_TX_C_DP<10>")
		)
		(pad "2" smd rect
			(at 0.2667 0 90)
			(size 0.3048 0.381)
			(layers "F.Cu" "F.Mask" "F.Paste")
			(net "P5E_CPU1_G1_TX_DP<10>")
		)
	)
	(footprint ""
		(layer "F.Cu")
		(at 388.649972 -178.0921 -90)
		(property "Reference" "PR349"
			(at 0 0 270)
			(layer "F.SilkS")
			(hide yes)
			(effects
				(font
					(size 1.27 1.27)
				)
			)
		)
		(property "Value" ""
			(at 0 0 270)
			(layer "F.Fab")
			(effects
				(font
					(size 1.27 1.27)
				)
			)
		)
		(duplicate_pad_numbers_are_jumpers no)
		(fp_line
			(start -0.7874 0.4064)
			(end -0.7874 -0.4064)
			(stroke
				(width 0.1524)
				(type default)
			)
			(layer "F.SilkS")
		)
		(fp_line
			(start 0.7874 0.4064)
			(end -0.7874 0.4064)
			(stroke
				(width 0.1524)
				(type default)
			)
			(layer "F.SilkS")
		)
		(fp_line
			(start -0.7874 -0.4064)
			(end 0.7874 -0.4064)
			(stroke
				(width 0.1524)
				(type default)
			)
			(layer "F.SilkS")
		)
		(fp_line
			(start 0.7874 -0.4064)
			(end 0.7874 0.4064)
			(stroke
				(width 0.1524)
				(type default)
			)
			(layer "F.SilkS")
		)
		(fp_line
			(start -0.67945 0.3048)
			(end -0.67945 -0.305054)
			(stroke
				(width 0.1)
				(type default)
			)
			(layer "F.Fab")
		)
		(fp_line
			(start -0.12065 0.3048)
			(end -0.67945 0.3048)
			(stroke
				(width 0.1)
				(type default)
			)
			(layer "F.Fab")
		)
		(fp_line
			(start 0.120396 0.3048)
			(end 0.120396 0.2794)
			(stroke
				(width 0.1)
				(type default)
			)
			(layer "F.Fab")
		)
		(fp_line
			(start 0.67945 0.3048)
			(end 0.120396 0.3048)
			(stroke
				(width 0.1)
				(type default)
			)
			(layer "F.Fab")
		)
		(fp_line
			(start -0.12065 0.2794)
			(end -0.12065 0.3048)
			(stroke
				(width 0.1)
				(type default)
			)
			(layer "F.Fab")
		)
		(fp_line
			(start 0.120396 0.2794)
			(end -0.12065 0.2794)
			(stroke
				(width 0.1)
				(type default)
			)
			(layer "F.Fab")
		)
		(fp_line
			(start -0.12065 -0.2794)
			(end 0.12065 -0.2794)
			(stroke
				(width 0.1)
				(type default)
			)
			(layer "F.Fab")
		)
		(fp_line
			(start 0.12065 -0.2794)
			(end 0.12065 -0.3048)
			(stroke
				(width 0.1)
				(type default)
			)
			(layer "F.Fab")
		)
		(fp_line
			(start 0.12065 -0.3048)
			(end 0.67945 -0.3048)
			(stroke
				(width 0.1)
				(type default)
			)
			(layer "F.Fab")
		)
		(fp_line
			(start 0.67945 -0.3048)
			(end 0.67945 0.3048)
			(stroke
				(width 0.1)
				(type default)
			)
			(layer "F.Fab")
		)
		(fp_line
			(start -0.67945 -0.305054)
			(end -0.12065 -0.305054)
			(stroke
				(width 0.1)
				(type default)
			)
			(layer "F.Fab")
		)
		(fp_line
			(start -0.12065 -0.305054)
			(end -0.12065 -0.2794)
			(stroke
				(width 0.1)
				(type default)
			)
			(layer "F.Fab")
		)
		(pad "1" smd circle
			(at -0.40005 0 270)
			(size 0 0)
			(layers "F.Cu" "F.Mask" "F.Paste")
			(net "SW_PVDDCR_CPU0_P0_BOOT4")
		)
		(pad "2" smd circle
			(at 0.40005 0 270)
			(size 0 0)
			(layers "F.Cu" "F.Mask" "F.Paste")
			(net "SW_PVDDCR_CPU0_P0_BOOT4_RC")
		)
	)
	(footprint ""
		(layer "F.Cu")
		(at 297.995594 -393.96416)
		(property "Reference" "R978"
			(at 0 0 0)
			(layer "F.SilkS")
			(hide yes)
			(effects
				(font
					(size 1.27 1.27)
				)
			)
		)
		(property "Value" ""
			(at 0 0 0)
			(layer "F.Fab")
			(effects
				(font
					(size 1.27 1.27)
				)
			)
		)
		(duplicate_pad_numbers_are_jumpers no)
		(fp_line
			(start -0.32512 -0.175006)
			(end 0.32512 -0.175006)
			(stroke
				(width 0.1)
				(type default)
			)
			(layer "F.Fab")
		)
		(fp_line
			(start -0.32512 0.175006)
			(end -0.32512 -0.175006)
			(stroke
				(width 0.1)
				(type default)
			)
			(layer "F.Fab")
		)
		(fp_line
			(start 0.32512 -0.175006)
			(end 0.32512 0.175006)
			(stroke
				(width 0.1)
				(type default)
			)
			(layer "F.Fab")
		)
		(fp_line
			(start 0.32512 0.175006)
			(end -0.32512 0.175006)
			(stroke
				(width 0.1)
				(type default)
			)
			(layer "F.Fab")
		)
		(pad "1" smd rect
			(at -0.2667 0)
			(size 0.3048 0.381)
			(layers "F.Cu" "F.Mask" "F.Paste")
			(net "P1V8_CPU0_RT_1D")
		)
		(pad "2" smd rect
			(at 0.2667 0 180)
			(size 0.3048 0.381)
			(layers "F.Cu" "F.Mask" "F.Paste")
			(net "GPIO2_RT_CPU0_P0")
		)
	)
	(footprint ""
		(layer "F.Cu")
		(at 278.006556 -438.001664 90)
		(property "Reference" "R4552"
			(at 0 0 90)
			(layer "F.SilkS")
			(hide yes)
			(effects
				(font
					(size 1.27 1.27)
				)
			)
		)
		(property "Value" ""
			(at 0 0 90)
			(layer "F.Fab")
			(effects
				(font
					(size 1.27 1.27)
				)
			)
		)
		(duplicate_pad_numbers_are_jumpers no)
		(fp_line
			(start 0.7874 -0.4064)
			(end 0.7874 0.4064)
			(stroke
				(width 0.1524)
				(type default)
			)
			(layer "F.SilkS")
		)
		(fp_line
			(start -0.7874 -0.4064)
			(end 0.7874 -0.4064)
			(stroke
				(width 0.1524)
				(type default)
			)
			(layer "F.SilkS")
		)
		(fp_line
			(start 0.7874 0.4064)
			(end -0.7874 0.4064)
			(stroke
				(width 0.1524)
				(type default)
			)
			(layer "F.SilkS")
		)
		(fp_line
			(start -0.7874 0.4064)
			(end -0.7874 -0.4064)
			(stroke
				(width 0.1524)
				(type default)
			)
			(layer "F.SilkS")
		)
		(fp_line
			(start -0.12065 -0.305054)
			(end -0.12065 -0.2794)
			(stroke
				(width 0.1)
				(type default)
			)
			(layer "F.Fab")
		)
		(fp_line
			(start -0.67945 -0.305054)
			(end -0.12065 -0.305054)
			(stroke
				(width 0.1)
				(type default)
			)
			(layer "F.Fab")
		)
		(fp_line
			(start 0.67945 -0.3048)
			(end 0.67945 0.3048)
			(stroke
				(width 0.1)
				(type default)
			)
			(layer "F.Fab")
		)
		(fp_line
			(start 0.12065 -0.3048)
			(end 0.67945 -0.3048)
			(stroke
				(width 0.1)
				(type default)
			)
			(layer "F.Fab")
		)
		(fp_line
			(start 0.12065 -0.2794)
			(end 0.12065 -0.3048)
			(stroke
				(width 0.1)
				(type default)
			)
			(layer "F.Fab")
		)
		(fp_line
			(start -0.12065 -0.2794)
			(end 0.12065 -0.2794)
			(stroke
				(width 0.1)
				(type default)
			)
			(layer "F.Fab")
		)
		(fp_line
			(start 0.120396 0.2794)
			(end -0.12065 0.2794)
			(stroke
				(width 0.1)
				(type default)
			)
			(layer "F.Fab")
		)
		(fp_line
			(start -0.12065 0.2794)
			(end -0.12065 0.3048)
			(stroke
				(width 0.1)
				(type default)
			)
			(layer "F.Fab")
		)
		(fp_line
			(start 0.67945 0.3048)
			(end 0.120396 0.3048)
			(stroke
				(width 0.1)
				(type default)
			)
			(layer "F.Fab")
		)
		(fp_line
			(start 0.120396 0.3048)
			(end 0.120396 0.2794)
			(stroke
				(width 0.1)
				(type default)
			)
			(layer "F.Fab")
		)
		(fp_line
			(start -0.12065 0.3048)
			(end -0.67945 0.3048)
			(stroke
				(width 0.1)
				(type default)
			)
			(layer "F.Fab")
		)
		(fp_line
			(start -0.67945 0.3048)
			(end -0.67945 -0.305054)
			(stroke
				(width 0.1)
				(type default)
			)
			(layer "F.Fab")
		)
		(pad "1" smd circle
			(at -0.40005 0 90)
			(size 0 0)
			(layers "F.Cu" "F.Mask" "F.Paste")
			(net "HPDB_HSC_PWRGD")
		)
		(pad "2" smd circle
			(at 0.40005 0 90)
			(size 0 0)
			(layers "F.Cu" "F.Mask" "F.Paste")
			(net "GND")
		)
	)
	(footprint ""
		(layer "F.Cu")
		(at 333.65948 -16.178276 90)
		(property "Reference" "D8"
			(at -3.48869 -0.212344 90)
			(unlocked yes)
			(layer "F.SilkS")
			(effects
				(font
					(size 0.7874 0.5842)
					(thickness 0.1524)
				)
				(justify left)
			)
		)
		(property "Value" ""
			(at 0 0 90)
			(layer "F.Fab")
			(effects
				(font
					(size 1.27 1.27)
				)
			)
		)
		(duplicate_pad_numbers_are_jumpers no)
		(fp_line
			(start 1.778 -0.5588)
			(end 1.3208 -0.5588)
			(stroke
				(width 0.1524)
				(type default)
			)
			(layer "F.SilkS")
		)
		(fp_line
			(start 1.778 -0.5588)
			(end 1.778 0.5588)
			(stroke
				(width 0.1524)
				(type default)
			)
			(layer "F.SilkS")
		)
		(fp_line
			(start 1.4732 -0.5588)
			(end 1.4732 0.5588)
			(stroke
				(width 0.1524)
				(type default)
			)
			(layer "F.SilkS")
		)
		(fp_line
			(start 1.3208 -0.5588)
			(end 1.3208 0.5588)
			(stroke
				(width 0.1524)
				(type default)
			)
			(layer "F.SilkS")
		)
		(fp_line
			(start -1.3208 -0.5588)
			(end 1.3208 -0.5588)
			(stroke
				(width 0.1524)
				(type default)
			)
			(layer "F.SilkS")
		)
		(fp_line
			(start 1.778 0.5588)
			(end 1.3208 0.5588)
			(stroke
				(width 0.1524)
				(type default)
			)
			(layer "F.SilkS")
		)
		(fp_line
			(start 1.6256 0.5588)
			(end 1.6256 -0.5588)
			(stroke
				(width 0.1524)
				(type default)
			)
			(layer "F.SilkS")
		)
		(fp_line
			(start 1.3208 0.5588)
			(end -1.3208 0.5588)
			(stroke
				(width 0.1524)
				(type default)
			)
			(layer "F.SilkS")
		)
		(fp_line
			(start -1.3208 0.5588)
			(end -1.3208 -0.5588)
			(stroke
				(width 0.1524)
				(type default)
			)
			(layer "F.SilkS")
		)
		(fp_line
			(start 0.899922 -0.40005)
			(end 0.899922 0.40005)
			(stroke
				(width 0.1)
				(type default)
			)
			(layer "F.Fab")
		)
		(fp_line
			(start -0.899922 -0.40005)
			(end 0.899922 -0.40005)
			(stroke
				(width 0.1)
				(type default)
			)
			(layer "F.Fab")
		)
		(fp_line
			(start 0.899922 0.40005)
			(end -0.899922 0.40005)
			(stroke
				(width 0.1)
				(type default)
			)
			(layer "F.Fab")
		)
		(fp_line
			(start -0.899922 0.40005)
			(end -0.899922 -0.40005)
			(stroke
				(width 0.1)
				(type default)
			)
			(layer "F.Fab")
		)
		(fp_text user "-"
			(at 1.651 -0.86233 90)
			(unlocked yes)
			(layer "F.SilkS")
			(effects
				(font
					(size 1.905 1.4224)
					(thickness 0.1524)
				)
				(justify left)
			)
		)
		(fp_text user "+"
			(at -2.466086 0.324104 90)
			(unlocked yes)
			(layer "F.SilkS")
			(effects
				(font
					(size 1.905 1.4224)
					(thickness 0.1524)
				)
				(justify left)
			)
		)
		(fp_text user "-"
			(at 1.651 -0.22225 90)
			(unlocked yes)
			(layer "F.Fab")
			(effects
				(font
					(size 1.905 1.4224)
					(thickness 0.1524)
				)
				(justify left)
			)
		)
		(fp_text user "+"
			(at -2.6162 -0.22225 90)
			(unlocked yes)
			(layer "F.Fab")
			(effects
				(font
					(size 1.905 1.4224)
					(thickness 0.1524)
				)
				(justify left)
			)
		)
		(pad "A" smd rect
			(at -0.750062 0 90)
			(size 0.8128 0.8128)
			(layers "F.Cu" "F.Mask" "F.Paste")
			(net "BMC_FPGA_LED1_R_N")
		)
		(pad "C" smd rect
			(at 0.750062 0 90)
			(size 0.8128 0.8128)
			(layers "F.Cu" "F.Mask" "F.Paste")
			(net "BMC_FPGA_LED1_N")
		)
	)
	(footprint ""
		(layer "F.Cu")
		(at 215.4301 -398.940782 180)
		(property "Reference" "PC2350"
			(at 0 0 180)
			(layer "F.SilkS")
			(hide yes)
			(effects
				(font
					(size 1.27 1.27)
				)
			)
		)
		(property "Value" ""
			(at 0 0 180)
			(layer "F.Fab")
			(effects
				(font
					(size 1.27 1.27)
				)
			)
		)
		(duplicate_pad_numbers_are_jumpers no)
		(fp_line
			(start 0.7874 0.4064)
			(end -0.7874 0.4064)
			(stroke
				(width 0.1524)
				(type default)
			)
			(layer "F.SilkS")
		)
		(fp_line
			(start 0.7874 -0.4064)
			(end 0.7874 0.4064)
			(stroke
				(width 0.1524)
				(type default)
			)
			(layer "F.SilkS")
		)
		(fp_line
			(start -0.7874 0.4064)
			(end -0.7874 -0.4064)
			(stroke
				(width 0.1524)
				(type default)
			)
			(layer "F.SilkS")
		)
		(fp_line
			(start -0.7874 -0.4064)
			(end 0.7874 -0.4064)
			(stroke
				(width 0.1524)
				(type default)
			)
			(layer "F.SilkS")
		)
		(fp_line
			(start 0.67945 0.3048)
			(end 0.120396 0.3048)
			(stroke
				(width 0.1)
				(type default)
			)
			(layer "F.Fab")
		)
		(fp_line
			(start 0.67945 -0.3048)
			(end 0.67945 0.3048)
			(stroke
				(width 0.1)
				(type default)
			)
			(layer "F.Fab")
		)
		(fp_line
			(start 0.12065 -0.2794)
			(end 0.12065 -0.3048)
			(stroke
				(width 0.1)
				(type default)
			)
			(layer "F.Fab")
		)
		(fp_line
			(start 0.12065 -0.3048)
			(end 0.67945 -0.3048)
			(stroke
				(width 0.1)
				(type default)
			)
			(layer "F.Fab")
		)
		(fp_line
			(start 0.120396 0.3048)
			(end 0.120396 0.2794)
			(stroke
				(width 0.1)
				(type default)
			)
			(layer "F.Fab")
		)
		(fp_line
			(start 0.120396 0.2794)
			(end -0.12065 0.2794)
			(stroke
				(width 0.1)
				(type default)
			)
			(layer "F.Fab")
		)
		(fp_line
			(start -0.12065 0.3048)
			(end -0.67945 0.3048)
			(stroke
				(width 0.1)
				(type default)
			)
			(layer "F.Fab")
		)
		(fp_line
			(start -0.12065 0.2794)
			(end -0.12065 0.3048)
			(stroke
				(width 0.1)
				(type default)
			)
			(layer "F.Fab")
		)
		(fp_line
			(start -0.12065 -0.2794)
			(end 0.12065 -0.2794)
			(stroke
				(width 0.1)
				(type default)
			)
			(layer "F.Fab")
		)
		(fp_line
			(start -0.12065 -0.305054)
			(end -0.12065 -0.2794)
			(stroke
				(width 0.1)
				(type default)
			)
			(layer "F.Fab")
		)
		(fp_line
			(start -0.67945 0.3048)
			(end -0.67945 -0.305054)
			(stroke
				(width 0.1)
				(type default)
			)
			(layer "F.Fab")
		)
		(fp_line
			(start -0.67945 -0.305054)
			(end -0.12065 -0.305054)
			(stroke
				(width 0.1)
				(type default)
			)
			(layer "F.Fab")
		)
		(pad "1" smd circle
			(at -0.40005 0 180)
			(size 0 0)
			(layers "F.Cu" "F.Mask" "F.Paste")
			(net "HSC_OCREF")
		)
		(pad "2" smd circle
			(at 0.40005 0 180)
			(size 0 0)
			(layers "F.Cu" "F.Mask" "F.Paste")
			(net "AGND_HSC")
		)
	)
	(footprint ""
		(layer "F.Cu")
		(at 315.771022 -32.572706 180)
		(property "Reference" "C59"
			(at 0 0 180)
			(layer "F.SilkS")
			(hide yes)
			(effects
				(font
					(size 1.27 1.27)
				)
			)
		)
		(property "Value" ""
			(at 0 0 180)
			(layer "F.Fab")
			(effects
				(font
					(size 1.27 1.27)
				)
			)
		)
		(duplicate_pad_numbers_are_jumpers no)
		(fp_line
			(start 0.7874 0.4064)
			(end -0.7874 0.4064)
			(stroke
				(width 0.1524)
				(type default)
			)
			(layer "F.SilkS")
		)
		(fp_line
			(start 0.7874 -0.4064)
			(end 0.7874 0.4064)
			(stroke
				(width 0.1524)
				(type default)
			)
			(layer "F.SilkS")
		)
		(fp_line
			(start -0.7874 0.4064)
			(end -0.7874 -0.4064)
			(stroke
				(width 0.1524)
				(type default)
			)
			(layer "F.SilkS")
		)
		(fp_line
			(start -0.7874 -0.4064)
			(end 0.7874 -0.4064)
			(stroke
				(width 0.1524)
				(type default)
			)
			(layer "F.SilkS")
		)
		(fp_line
			(start 0.67945 0.3048)
			(end 0.120396 0.3048)
			(stroke
				(width 0.1)
				(type default)
			)
			(layer "F.Fab")
		)
		(fp_line
			(start 0.67945 -0.3048)
			(end 0.67945 0.3048)
			(stroke
				(width 0.1)
				(type default)
			)
			(layer "F.Fab")
		)
		(fp_line
			(start 0.12065 -0.2794)
			(end 0.12065 -0.3048)
			(stroke
				(width 0.1)
				(type default)
			)
			(layer "F.Fab")
		)
		(fp_line
			(start 0.12065 -0.3048)
			(end 0.67945 -0.3048)
			(stroke
				(width 0.1)
				(type default)
			)
			(layer "F.Fab")
		)
		(fp_line
			(start 0.120396 0.3048)
			(end 0.120396 0.2794)
			(stroke
				(width 0.1)
				(type default)
			)
			(layer "F.Fab")
		)
		(fp_line
			(start 0.120396 0.2794)
			(end -0.12065 0.2794)
			(stroke
				(width 0.1)
				(type default)
			)
			(layer "F.Fab")
		)
		(fp_line
			(start -0.12065 0.3048)
			(end -0.67945 0.3048)
			(stroke
				(width 0.1)
				(type default)
			)
			(layer "F.Fab")
		)
		(fp_line
			(start -0.12065 0.2794)
			(end -0.12065 0.3048)
			(stroke
				(width 0.1)
				(type default)
			)
			(layer "F.Fab")
		)
		(fp_line
			(start -0.12065 -0.2794)
			(end 0.12065 -0.2794)
			(stroke
				(width 0.1)
				(type default)
			)
			(layer "F.Fab")
		)
		(fp_line
			(start -0.12065 -0.305054)
			(end -0.12065 -0.2794)
			(stroke
				(width 0.1)
				(type default)
			)
			(layer "F.Fab")
		)
		(fp_line
			(start -0.67945 0.3048)
			(end -0.67945 -0.305054)
			(stroke
				(width 0.1)
				(type default)
			)
			(layer "F.Fab")
		)
		(fp_line
			(start -0.67945 -0.305054)
			(end -0.12065 -0.305054)
			(stroke
				(width 0.1)
				(type default)
			)
			(layer "F.Fab")
		)
		(pad "1" smd circle
			(at -0.40005 0 180)
			(size 0 0)
			(layers "F.Cu" "F.Mask" "F.Paste")
			(net "P12V_OCP_V3_2_ISENSE_MAM")
		)
		(pad "2" smd circle
			(at 0.40005 0 180)
			(size 0 0)
			(layers "F.Cu" "F.Mask" "F.Paste")
			(net "GND")
		)
	)
)
